# BASEBOARD_FAB2 (Tioga Pass) — schematic netlist excerpt (pin names and nets, part order shuffled) for the footprints in the layout excerpt that follows; sources: Cadence DE-HDL packaged netlist, KiCad conversion of Wiwynn_Tioga_Pass_MB.brd

R6W17  RES  0.0 5% CHIP  pkg 0402  page 145 : A = SMB_DEBUG_STBY_LVC3_SCL ; B = SMB_DEBUG_STBY_LVC3_SCL_R
C6F2  CAP_A  0.1UF 16V 10% X7R  pkg 0402V  page 99 : A = PVCCIO_CPU0 ; B = GND
R1T12  RES  1.00K 1% CHIP  pkg 0402  page 164 : A = FM_BOARD_REV_ID1 ; B = GND

(kicad_pcb
	(version 20260206)
	(generator "pcbnew")
	(generator_version "10.0")
	(general
		(thickness 1.6)
		(legacy_teardrops no)
	)
	(paper "A4")
	(title_block
		(title "Wiwynn_Tioga_Pass_MB.brd")
		(comment 1 "Tioga Pass / footprints 1655-1657 of 4770")
	)
	(layers
		(0 "F.Cu" signal "TOP")
		(4 "In1.Cu" signal "L2GND")
		(6 "In2.Cu" signal "L3")
		(8 "In3.Cu" signal "L4GND")
		(10 "In4.Cu" signal "L5")
		(12 "In5.Cu" signal "L6GND")
		(14 "In6.Cu" signal "L7VCC")
		(16 "In7.Cu" signal "L8VCC")
		(18 "In8.Cu" signal "L9GND")
		(20 "In9.Cu" signal "L10")
		(22 "In10.Cu" signal "L11GND")
		(24 "In11.Cu" signal "L12")
		(26 "In12.Cu" signal "L13GND")
		(2 "B.Cu" signal "BOTTOM")
		(9 "F.Adhes" user "F.Adhesive")
		(11 "B.Adhes" user "B.Adhesive")
		(13 "F.Paste" user "Package Geometry/Pastemask Top")
		(15 "B.Paste" user "Package Geometry/Pastemask Bottom")
		(5 "F.SilkS" user "Ref Des/Silkscreen Top")
		(7 "B.SilkS" user "Ref Des/Silkscreen Bottom")
		(1 "F.Mask" user "Board Geometry/Soldermask Top")
		(3 "B.Mask" user "Board Geometry/Soldermask Bottom")
		(17 "Dwgs.User" user "User.Drawings")
		(19 "Cmts.User" user "User.Comments")
		(21 "Eco1.User" user "User.Eco1")
		(23 "Eco2.User" user "User.Eco2")
		(25 "Edge.Cuts" user "Board Geometry/Outline")
		(27 "Margin" user)
		(31 "F.CrtYd" user "Package Geometry/Place Bound Top")
		(29 "B.CrtYd" user "Package Geometry/Place Bound Bottom")
		(35 "F.Fab" user "Ref Des/Assembly Top")
		(33 "B.Fab" user "Ref Des/Assembly Bottom")
	)
	(footprint ""
		(layer "F.Cu")
		(at 401.472146 -37.220652 90)
		(property "Reference" "R6W17"
			(at -0.8382 -0.67818 90)
			(unlocked yes)
			(layer "F.SilkS")
			(effects
				(font
					(size 0.4064 0.254)
					(thickness 0.1524)
				)
				(justify left)
			)
		)
		(property "Value" ""
			(at 0 0 90)
			(layer "F.Fab")
			(effects
				(font
					(size 1.27 1.27)
				)
			)
		)
		(duplicate_pad_numbers_are_jumpers no)
		(fp_poly
			(pts
				(xy -0.2794 -0.1016) (xy 0.2794 -0.1016) (xy 0.2794 0.9906) (xy -0.2794 0.9906)
			)
			(stroke
				(width 0)
				(type default)
			)
			(fill no)
			(layer "F.CrtYd")
		)
		(fp_line
			(start 0.2794 -0.1016)
			(end -0.2794 -0.1016)
			(stroke
				(width 0.1)
				(type default)
			)
			(layer "F.Fab")
		)
		(fp_line
			(start -0.2794 -0.1016)
			(end -0.2794 0.9906)
			(stroke
				(width 0.1)
				(type default)
			)
			(layer "F.Fab")
		)
		(fp_line
			(start 0.2794 0.9906)
			(end 0.2794 -0.1016)
			(stroke
				(width 0.1)
				(type default)
			)
			(layer "F.Fab")
		)
		(fp_line
			(start -0.2794 0.9906)
			(end 0.2794 0.9906)
			(stroke
				(width 0.1)
				(type default)
			)
			(layer "F.Fab")
		)
		(pad "1" smd rect
			(at 0 0 90)
			(size 0.508 0.508)
			(layers "F.Cu" "F.Mask" "F.Paste")
			(net "SMB_DEBUG_STBY_LVC3_SCL")
		)
		(pad "2" smd rect
			(at 0 0.889 90)
			(size 0.508 0.508)
			(layers "F.Cu" "F.Mask" "F.Paste")
			(net "SMB_DEBUG_STBY_LVC3_SCL_R")
		)
		(zone
			(layer "F.Cu")
			(hatch none 0.5)
			(connect_pads
				(clearance 0)
			)
			(min_thickness 0.25)
			(keepout
				(tracks allowed)
				(vias not_allowed)
				(pads allowed)
				(copperpour not_allowed)
				(footprints allowed)
			)
			(placement
				(enabled no)
				(sheetname "")
			)
			(fill
				(thermal_gap 0.5)
				(thermal_bridge_width 0.5)
				(island_removal_mode 0)
			)
			(polygon
				(pts
					(xy 401.726146 -36.966652) (xy 401.726146 -37.474652) (xy 402.107146 -37.474652) (xy 402.107146 -36.966652)
				)
			)
		)
		(zone
			(layer "F.Cu")
			(hatch none 0.5)
			(connect_pads
				(clearance 0)
			)
			(min_thickness 0.25)
			(keepout
				(tracks not_allowed)
				(vias allowed)
				(pads allowed)
				(copperpour not_allowed)
				(footprints allowed)
			)
			(placement
				(enabled no)
				(sheetname "")
			)
			(fill
				(thermal_gap 0.5)
				(thermal_bridge_width 0.5)
				(island_removal_mode 0)
			)
			(polygon
				(pts
					(xy 402.107146 -36.966652) (xy 402.107146 -37.474652) (xy 401.726146 -37.474652) (xy 401.726146 -36.966652)
				)
			)
		)
	)
	(footprint ""
		(layer "F.Cu")
		(at 325.0057 -31.15818)
		(property "Reference" "C6F2"
			(at 0 0 0)
			(layer "F.SilkS")
			(hide yes)
			(effects
				(font
					(size 1.27 1.27)
				)
			)
		)
		(property "Value" ""
			(at 0 0 0)
			(layer "F.Fab")
			(effects
				(font
					(size 1.27 1.27)
				)
			)
		)
		(duplicate_pad_numbers_are_jumpers no)
		(fp_poly
			(pts
				(xy 0.3048 -0.1016) (xy 0.3048 0.9906) (xy -0.3048 0.9906) (xy -0.3048 -0.1016)
			)
			(stroke
				(width 0)
				(type default)
			)
			(fill no)
			(layer "F.CrtYd")
		)
		(fp_line
			(start -0.3048 -0.1016)
			(end -0.3048 0.9906)
			(stroke
				(width 0.1)
				(type default)
			)
			(layer "F.Fab")
		)
		(fp_line
			(start -0.3048 0.9906)
			(end 0.3048 0.9906)
			(stroke
				(width 0.1)
				(type default)
			)
			(layer "F.Fab")
		)
		(fp_line
			(start 0.3048 -0.1016)
			(end -0.3048 -0.1016)
			(stroke
				(width 0.1)
				(type default)
			)
			(layer "F.Fab")
		)
		(fp_line
			(start 0.3048 0.9906)
			(end 0.3048 -0.1016)
			(stroke
				(width 0.1)
				(type default)
			)
			(layer "F.Fab")
		)
		(pad "1" smd rect
			(at 0 0)
			(size 0.508 0.508)
			(layers "F.Cu" "F.Mask" "F.Paste")
			(net "PVCCIO_CPU0")
		)
		(pad "2" smd rect
			(at 0 0.889)
			(size 0.508 0.508)
			(layers "F.Cu" "F.Mask" "F.Paste")
			(net "GND")
		)
		(zone
			(layer "F.Cu")
			(hatch none 0.5)
			(connect_pads
				(clearance 0)
			)
			(min_thickness 0.25)
			(keepout
				(tracks allowed)
				(vias not_allowed)
				(pads allowed)
				(copperpour not_allowed)
				(footprints allowed)
			)
			(placement
				(enabled no)
				(sheetname "")
			)
			(fill
				(thermal_gap 0.5)
				(thermal_bridge_width 0.5)
				(island_removal_mode 0)
			)
			(polygon
				(pts
					(xy 324.7517 -30.90418) (xy 325.2597 -30.90418) (xy 325.2597 -30.52318) (xy 324.7517 -30.52318)
				)
			)
		)
		(zone
			(layer "F.Cu")
			(hatch none 0.5)
			(connect_pads
				(clearance 0)
			)
			(min_thickness 0.25)
			(keepout
				(tracks not_allowed)
				(vias allowed)
				(pads allowed)
				(copperpour not_allowed)
				(footprints allowed)
			)
			(placement
				(enabled no)
				(sheetname "")
			)
			(fill
				(thermal_gap 0.5)
				(thermal_bridge_width 0.5)
				(island_removal_mode 0)
			)
			(polygon
				(pts
					(xy 324.7517 -30.52318) (xy 325.2597 -30.52318) (xy 325.2597 -30.90418) (xy 324.7517 -30.90418)
				)
			)
		)
	)
	(footprint ""
		(layer "F.Cu")
		(at 408.161236 -47.825914 180)
		(property "Reference" "R1T12"
			(at 0 0 180)
			(layer "F.SilkS")
			(hide yes)
			(effects
				(font
					(size 1.27 1.27)
				)
			)
		)
		(property "Value" ""
			(at 0 0 180)
			(layer "F.Fab")
			(effects
				(font
					(size 1.27 1.27)
				)
			)
		)
		(duplicate_pad_numbers_are_jumpers no)
		(fp_poly
			(pts
				(xy -0.2794 -0.1016) (xy 0.2794 -0.1016) (xy 0.2794 0.9906) (xy -0.2794 0.9906)
			)
			(stroke
				(width 0)
				(type default)
			)
			(fill no)
			(layer "F.CrtYd")
		)
		(fp_line
			(start 0.2794 0.9906)
			(end 0.2794 -0.1016)
			(stroke
				(width 0.1)
				(type default)
			)
			(layer "F.Fab")
		)
		(fp_line
			(start 0.2794 -0.1016)
			(end -0.2794 -0.1016)
			(stroke
				(width 0.1)
				(type default)
			)
			(layer "F.Fab")
		)
		(fp_line
			(start -0.2794 0.9906)
			(end 0.2794 0.9906)
			(stroke
				(width 0.1)
				(type default)
			)
			(layer "F.Fab")
		)
		(fp_line
			(start -0.2794 -0.1016)
			(end -0.2794 0.9906)
			(stroke
				(width 0.1)
				(type default)
			)
			(layer "F.Fab")
		)
		(pad "1" smd rect
			(at 0 0 180)
			(size 0.508 0.508)
			(layers "F.Cu" "F.Mask" "F.Paste")
			(net "FM_BOARD_REV_ID1")
		)
		(pad "2" smd rect
			(at 0 0.889 180)
			(size 0.508 0.508)
			(layers "F.Cu" "F.Mask" "F.Paste")
			(net "GND")
		)
	)
)
